(kicad_pcb
	(version 20260206)
	(generator "pcbnew")
	(generator_version "10.0")
	(general
		(thickness 1.6)
		(legacy_teardrops no)
	)
	(paper "A4")
	(title_block
		(title "Wiwynn_Tioga_Pass_MB.brd")
		(comment 1 "Tioga Pass / footprints 1569-1576 of 4770")
	)
	(layers
		(0 "F.Cu" signal "TOP")
		(4 "In1.Cu" signal "L2GND")
		(6 "In2.Cu" signal "L3")
		(8 "In3.Cu" signal "L4GND")
		(10 "In4.Cu" signal "L5")
		(12 "In5.Cu" signal "L6GND")
		(14 "In6.Cu" signal "L7VCC")
		(16 "In7.Cu" signal "L8VCC")
		(18 "In8.Cu" signal "L9GND")
		(20 "In9.Cu" signal "L10")
		(22 "In10.Cu" signal "L11GND")
		(24 "In11.Cu" signal "L12")
		(26 "In12.Cu" signal "L13GND")
		(2 "B.Cu" signal "BOTTOM")
		(9 "F.Adhes" user "F.Adhesive")
		(11 "B.Adhes" user "B.Adhesive")
		(13 "F.Paste" user "Package Geometry/Pastemask Top")
		(15 "B.Paste" user "Package Geometry/Pastemask Bottom")
		(5 "F.SilkS" user "Ref Des/Silkscreen Top")
		(7 "B.SilkS" user "Ref Des/Silkscreen Bottom")
		(1 "F.Mask" user "Board Geometry/Soldermask Top")
		(3 "B.Mask" user "Board Geometry/Soldermask Bottom")
		(17 "Dwgs.User" user "User.Drawings")
		(19 "Cmts.User" user "User.Comments")
		(21 "Eco1.User" user "User.Eco1")
		(23 "Eco2.User" user "User.Eco2")
		(25 "Edge.Cuts" user "Board Geometry/Outline")
		(27 "Margin" user)
		(31 "F.CrtYd" user "Package Geometry/Place Bound Top")
		(29 "B.CrtYd" user "Package Geometry/Place Bound Bottom")
		(35 "F.Fab" user "Ref Des/Assembly Top")
		(33 "B.Fab" user "Ref Des/Assembly Bottom")
	)
	(footprint ""
		(layer "F.Cu")
		(at 266.397232 -149.8092 90)
		(property "Reference" "C5A6"
			(at 1.848866 0.752348 90)
			(unlocked yes)
			(layer "F.SilkS")
			(effects
				(font
					(size 1.27 0.9652)
					(thickness 0.1524)
				)
			)
		)
		(property "Value" ""
			(at 0 0 90)
			(layer "F.Fab")
			(effects
				(font
					(size 1.27 1.27)
				)
			)
		)
		(duplicate_pad_numbers_are_jumpers no)
		(fp_rect
			(start -0.500126 1.598422)
			(end 0.500126 -0.201422)
			(stroke
				(width 0)
				(type default)
			)
			(fill no)
			(layer "F.CrtYd")
		)
		(fp_line
			(start 0.500126 -0.201422)
			(end 0.500126 1.598422)
			(stroke
				(width 0.1)
				(type default)
			)
			(layer "F.Fab")
		)
		(fp_line
			(start -0.500126 -0.201422)
			(end 0.500126 -0.201422)
			(stroke
				(width 0.1)
				(type default)
			)
			(layer "F.Fab")
		)
		(fp_line
			(start 0.500126 1.598422)
			(end -0.500126 1.598422)
			(stroke
				(width 0.1)
				(type default)
			)
			(layer "F.Fab")
		)
		(fp_line
			(start -0.500126 1.598422)
			(end -0.500126 -0.201422)
			(stroke
				(width 0.1)
				(type default)
			)
			(layer "F.Fab")
		)
		(pad "1" smd rect
			(at 0 0)
			(size 0.889 0.9906)
			(layers "F.Cu" "F.Mask" "F.Paste")
			(net "PVDDQ_DEF")
		)
		(pad "2" smd rect
			(at 0 1.397)
			(size 0.889 0.9906)
			(layers "F.Cu" "F.Mask" "F.Paste")
			(net "GND")
		)
		(zone
			(layer "F.Cu")
			(hatch none 0.5)
			(connect_pads
				(clearance 0)
			)
			(min_thickness 0.25)
			(keepout
				(tracks not_allowed)
				(vias allowed)
				(pads allowed)
				(copperpour not_allowed)
				(footprints allowed)
			)
			(placement
				(enabled no)
				(sheetname "")
			)
			(fill
				(thermal_gap 0.5)
				(thermal_bridge_width 0.5)
				(island_removal_mode 0)
			)
			(polygon
				(pts
					(xy 267.349732 -149.3139) (xy 267.349732 -150.3045) (xy 266.841732 -150.3045) (xy 266.841732 -149.3139)
				)
			)
		)
		(zone
			(layer "F.Cu")
			(hatch none 0.5)
			(connect_pads
				(clearance 0)
			)
			(min_thickness 0.25)
			(keepout
				(tracks allowed)
				(vias not_allowed)
				(pads allowed)
				(copperpour not_allowed)
				(footprints allowed)
			)
			(placement
				(enabled no)
				(sheetname "")
			)
			(fill
				(thermal_gap 0.5)
				(thermal_bridge_width 0.5)
				(island_removal_mode 0)
			)
			(polygon
				(pts
					(xy 267.349732 -149.3139) (xy 267.349732 -150.3045) (xy 266.841732 -150.3045) (xy 266.841732 -149.3139)
				)
			)
		)
	)
	(footprint ""
		(layer "F.Cu")
		(at 349.123 -14.859 90)
		(property "Reference" "R7G8"
			(at 0 0 90)
			(layer "F.SilkS")
			(hide yes)
			(effects
				(font
					(size 1.27 1.27)
				)
			)
		)
		(property "Value" ""
			(at 0 0 90)
			(layer "F.Fab")
			(effects
				(font
					(size 1.27 1.27)
				)
			)
		)
		(duplicate_pad_numbers_are_jumpers no)
		(fp_poly
			(pts
				(xy -0.2794 -0.1016) (xy 0.2794 -0.1016) (xy 0.2794 0.9906) (xy -0.2794 0.9906)
			)
			(stroke
				(width 0)
				(type default)
			)
			(fill no)
			(layer "F.CrtYd")
		)
		(fp_line
			(start 0.2794 -0.1016)
			(end -0.2794 -0.1016)
			(stroke
				(width 0.1)
				(type default)
			)
			(layer "F.Fab")
		)
		(fp_line
			(start -0.2794 -0.1016)
			(end -0.2794 0.9906)
			(stroke
				(width 0.1)
				(type default)
			)
			(layer "F.Fab")
		)
		(fp_line
			(start 0.2794 0.9906)
			(end 0.2794 -0.1016)
			(stroke
				(width 0.1)
				(type default)
			)
			(layer "F.Fab")
		)
		(fp_line
			(start -0.2794 0.9906)
			(end 0.2794 0.9906)
			(stroke
				(width 0.1)
				(type default)
			)
			(layer "F.Fab")
		)
		(pad "1" smd rect
			(at 0 0 90)
			(size 0.508 0.508)
			(layers "F.Cu" "F.Mask" "F.Paste")
			(net "VR_PVDDQ_ABC_XADDR1")
		)
		(pad "2" smd rect
			(at 0 0.889 90)
			(size 0.508 0.508)
			(layers "F.Cu" "F.Mask" "F.Paste")
			(net "GND")
		)
		(zone
			(layer "F.Cu")
			(hatch none 0.5)
			(connect_pads
				(clearance 0)
			)
			(min_thickness 0.25)
			(keepout
				(tracks allowed)
				(vias not_allowed)
				(pads allowed)
				(copperpour not_allowed)
				(footprints allowed)
			)
			(placement
				(enabled no)
				(sheetname "")
			)
			(fill
				(thermal_gap 0.5)
				(thermal_bridge_width 0.5)
				(island_removal_mode 0)
			)
			(polygon
				(pts
					(xy 349.377 -14.605) (xy 349.377 -15.113) (xy 349.758 -15.113) (xy 349.758 -14.605)
				)
			)
		)
		(zone
			(layer "F.Cu")
			(hatch none 0.5)
			(connect_pads
				(clearance 0)
			)
			(min_thickness 0.25)
			(keepout
				(tracks not_allowed)
				(vias allowed)
				(pads allowed)
				(copperpour not_allowed)
				(footprints allowed)
			)
			(placement
				(enabled no)
				(sheetname "")
			)
			(fill
				(thermal_gap 0.5)
				(thermal_bridge_width 0.5)
				(island_removal_mode 0)
			)
			(polygon
				(pts
					(xy 349.758 -14.605) (xy 349.758 -15.113) (xy 349.377 -15.113) (xy 349.377 -14.605)
				)
			)
		)
	)
	(footprint ""
		(layer "F.Cu")
		(at 273.168872 -73.318116)
		(property "Reference" "C5D48"
			(at 0 0 0)
			(layer "F.SilkS")
			(hide yes)
			(effects
				(font
					(size 1.27 1.27)
				)
			)
		)
		(property "Value" ""
			(at 0 0 0)
			(layer "F.Fab")
			(effects
				(font
					(size 1.27 1.27)
				)
			)
		)
		(duplicate_pad_numbers_are_jumpers no)
		(fp_poly
			(pts
				(xy -0.4953 -0.2032) (xy 0.4953 -0.2032) (xy 0.4953 1.6002) (xy -0.4953 1.6002)
			)
			(stroke
				(width 0)
				(type default)
			)
			(fill no)
			(layer "F.CrtYd")
		)
		(fp_line
			(start -0.4953 -0.2032)
			(end 0.4953 -0.2032)
			(stroke
				(width 0.1)
				(type default)
			)
			(layer "F.Fab")
		)
		(fp_line
			(start -0.4953 1.6002)
			(end -0.4953 -0.2032)
			(stroke
				(width 0.1)
				(type default)
			)
			(layer "F.Fab")
		)
		(fp_line
			(start 0.4953 -0.2032)
			(end 0.4953 1.6002)
			(stroke
				(width 0.1)
				(type default)
			)
			(layer "F.Fab")
		)
		(fp_line
			(start 0.4953 1.6002)
			(end -0.4953 1.6002)
			(stroke
				(width 0.1)
				(type default)
			)
			(layer "F.Fab")
		)
		(pad "1" smd rect
			(at 0 0)
			(size 0.762 0.889)
			(layers "F.Cu" "F.Mask" "F.Paste")
			(net "PVCCMCP_CPU0")
		)
		(pad "2" smd rect
			(at 0 1.397)
			(size 0.762 0.889)
			(layers "F.Cu" "F.Mask" "F.Paste")
			(net "GND")
		)
		(zone
			(layer "F.Cu")
			(hatch none 0.5)
			(connect_pads
				(clearance 0)
			)
			(min_thickness 0.25)
			(keepout
				(tracks not_allowed)
				(vias allowed)
				(pads allowed)
				(copperpour not_allowed)
				(footprints allowed)
			)
			(placement
				(enabled no)
				(sheetname "")
			)
			(fill
				(thermal_gap 0.5)
				(thermal_bridge_width 0.5)
				(island_removal_mode 0)
			)
			(polygon
				(pts
					(xy 272.787872 -72.873616) (xy 273.549872 -72.873616) (xy 273.549872 -72.365616) (xy 272.787872 -72.365616)
				)
			)
		)
	)
	(footprint ""
		(layer "F.Cu")
		(at 465.836 -134.366 180)
		(property "Reference" "R9B9"
			(at 0 0 180)
			(layer "F.SilkS")
			(hide yes)
			(effects
				(font
					(size 1.27 1.27)
				)
			)
		)
		(property "Value" ""
			(at 0 0 180)
			(layer "F.Fab")
			(effects
				(font
					(size 1.27 1.27)
				)
			)
		)
		(duplicate_pad_numbers_are_jumpers no)
		(fp_poly
			(pts
				(xy -0.2794 -0.1016) (xy 0.2794 -0.1016) (xy 0.2794 0.9906) (xy -0.2794 0.9906)
			)
			(stroke
				(width 0)
				(type default)
			)
			(fill no)
			(layer "F.CrtYd")
		)
		(fp_line
			(start 0.2794 0.9906)
			(end 0.2794 -0.1016)
			(stroke
				(width 0.1)
				(type default)
			)
			(layer "F.Fab")
		)
		(fp_line
			(start 0.2794 -0.1016)
			(end -0.2794 -0.1016)
			(stroke
				(width 0.1)
				(type default)
			)
			(layer "F.Fab")
		)
		(fp_line
			(start -0.2794 0.9906)
			(end 0.2794 0.9906)
			(stroke
				(width 0.1)
				(type default)
			)
			(layer "F.Fab")
		)
		(fp_line
			(start -0.2794 -0.1016)
			(end -0.2794 0.9906)
			(stroke
				(width 0.1)
				(type default)
			)
			(layer "F.Fab")
		)
		(pad "1" smd rect
			(at 0 0 180)
			(size 0.508 0.508)
			(layers "F.Cu" "F.Mask" "F.Paste")
			(net "JTAG_MCP_TCK")
		)
		(pad "2" smd rect
			(at 0 0.889 180)
			(size 0.508 0.508)
			(layers "F.Cu" "F.Mask" "F.Paste")
			(net "GND")
		)
		(zone
			(layer "F.Cu")
			(hatch none 0.5)
			(connect_pads
				(clearance 0)
			)
			(min_thickness 0.25)
			(keepout
				(tracks not_allowed)
				(vias allowed)
				(pads allowed)
				(copperpour not_allowed)
				(footprints allowed)
			)
			(placement
				(enabled no)
				(sheetname "")
			)
			(fill
				(thermal_gap 0.5)
				(thermal_bridge_width 0.5)
				(island_removal_mode 0)
			)
			(polygon
				(pts
					(xy 466.09 -135.001) (xy 465.582 -135.001) (xy 465.582 -134.62) (xy 466.09 -134.62)
				)
			)
		)
		(zone
			(layer "F.Cu")
			(hatch none 0.5)
			(connect_pads
				(clearance 0)
			)
			(min_thickness 0.25)
			(keepout
				(tracks allowed)
				(vias not_allowed)
				(pads allowed)
				(copperpour not_allowed)
				(footprints allowed)
			)
			(placement
				(enabled no)
				(sheetname "")
			)
			(fill
				(thermal_gap 0.5)
				(thermal_bridge_width 0.5)
				(island_removal_mode 0)
			)
			(polygon
				(pts
					(xy 466.09 -134.62) (xy 465.582 -134.62) (xy 465.582 -135.001) (xy 466.09 -135.001)
				)
			)
		)
	)
	(footprint ""
		(layer "F.Cu")
		(at 188.2775 -74.295 -90)
		(property "Reference" "RF6"
			(at -0.8382 -0.67818 270)
			(unlocked yes)
			(layer "F.SilkS")
			(effects
				(font
					(size 0.4064 0.254)
					(thickness 0.1524)
				)
				(justify left)
			)
		)
		(property "Value" ""
			(at 0 0 270)
			(layer "F.Fab")
			(effects
				(font
					(size 1.27 1.27)
				)
			)
		)
		(duplicate_pad_numbers_are_jumpers no)
		(fp_poly
			(pts
				(xy -0.2794 -0.1016) (xy 0.2794 -0.1016) (xy 0.2794 0.9906) (xy -0.2794 0.9906)
			)
			(stroke
				(width 0)
				(type default)
			)
			(fill no)
			(layer "F.CrtYd")
		)
		(fp_line
			(start -0.2794 0.9906)
			(end 0.2794 0.9906)
			(stroke
				(width 0.1)
				(type default)
			)
			(layer "F.Fab")
		)
		(fp_line
			(start 0.2794 0.9906)
			(end 0.2794 -0.1016)
			(stroke
				(width 0.1)
				(type default)
			)
			(layer "F.Fab")
		)
		(fp_line
			(start -0.2794 -0.1016)
			(end -0.2794 0.9906)
			(stroke
				(width 0.1)
				(type default)
			)
			(layer "F.Fab")
		)
		(fp_line
			(start 0.2794 -0.1016)
			(end -0.2794 -0.1016)
			(stroke
				(width 0.1)
				(type default)
			)
			(layer "F.Fab")
		)
		(pad "1" smd rect
			(at 0 0 270)
			(size 0.508 0.508)
			(layers "F.Cu" "F.Mask" "F.Paste")
			(net "VR_PVSA_CPU0_BIREF1")
		)
		(pad "2" smd rect
			(at 0 0.889 270)
			(size 0.508 0.508)
			(layers "F.Cu" "F.Mask" "F.Paste")
			(net "ISENSE_PVSA_CPU0_IMON")
		)
		(zone
			(layer "F.Cu")
			(hatch none 0.5)
			(connect_pads
				(clearance 0)
			)
			(min_thickness 0.25)
			(keepout
				(tracks not_allowed)
				(vias allowed)
				(pads allowed)
				(copperpour not_allowed)
				(footprints allowed)
			)
			(placement
				(enabled no)
				(sheetname "")
			)
			(fill
				(thermal_gap 0.5)
				(thermal_bridge_width 0.5)
				(island_removal_mode 0)
			)
			(polygon
				(pts
					(xy 187.6425 -74.549) (xy 187.6425 -74.041) (xy 188.0235 -74.041) (xy 188.0235 -74.549)
				)
			)
		)
		(zone
			(layer "F.Cu")
			(hatch none 0.5)
			(connect_pads
				(clearance 0)
			)
			(min_thickness 0.25)
			(keepout
				(tracks allowed)
				(vias not_allowed)
				(pads allowed)
				(copperpour not_allowed)
				(footprints allowed)
			)
			(placement
				(enabled no)
				(sheetname "")
			)
			(fill
				(thermal_gap 0.5)
				(thermal_bridge_width 0.5)
				(island_removal_mode 0)
			)
			(polygon
				(pts
					(xy 188.0235 -74.549) (xy 188.0235 -74.041) (xy 187.6425 -74.041) (xy 187.6425 -74.549)
				)
			)
		)
	)
	(footprint ""
		(layer "F.Cu")
		(at 38.40734 -93.8276 -90)
		(property "Reference" "CT56"
			(at -0.8382 -0.67818 270)
			(unlocked yes)
			(layer "F.SilkS")
			(effects
				(font
					(size 0.4064 0.254)
					(thickness 0.1524)
				)
				(justify left)
			)
		)
		(property "Value" ""
			(at 0 0 270)
			(layer "F.Fab")
			(effects
				(font
					(size 1.27 1.27)
				)
			)
		)
		(duplicate_pad_numbers_are_jumpers no)
		(fp_poly
			(pts
				(xy 0.3048 -0.1016) (xy 0.3048 0.9906) (xy -0.3048 0.9906) (xy -0.3048 -0.1016)
			)
			(stroke
				(width 0)
				(type default)
			)
			(fill no)
			(layer "F.CrtYd")
		)
		(fp_line
			(start -0.3048 0.9906)
			(end 0.3048 0.9906)
			(stroke
				(width 0.1)
				(type default)
			)
			(layer "F.Fab")
		)
		(fp_line
			(start 0.3048 0.9906)
			(end 0.3048 -0.1016)
			(stroke
				(width 0.1)
				(type default)
			)
			(layer "F.Fab")
		)
		(fp_line
			(start -0.3048 -0.1016)
			(end -0.3048 0.9906)
			(stroke
				(width 0.1)
				(type default)
			)
			(layer "F.Fab")
		)
		(fp_line
			(start 0.3048 -0.1016)
			(end -0.3048 -0.1016)
			(stroke
				(width 0.1)
				(type default)
			)
			(layer "F.Fab")
		)
		(pad "1" smd rect
			(at 0 0 270)
			(size 0.508 0.508)
			(layers "F.Cu" "F.Mask" "F.Paste")
			(net "VR_PVSA_CPU1_PHASE_SW")
		)
		(pad "2" smd rect
			(at 0 0.889 270)
			(size 0.508 0.508)
			(layers "F.Cu" "F.Mask" "F.Paste")
			(net "VR_PVSA_CPU1_PHASE_SW_RC")
		)
		(zone
			(layer "F.Cu")
			(hatch none 0.5)
			(connect_pads
				(clearance 0)
			)
			(min_thickness 0.25)
			(keepout
				(tracks not_allowed)
				(vias allowed)
				(pads allowed)
				(copperpour not_allowed)
				(footprints allowed)
			)
			(placement
				(enabled no)
				(sheetname "")
			)
			(fill
				(thermal_gap 0.5)
				(thermal_bridge_width 0.5)
				(island_removal_mode 0)
			)
			(polygon
				(pts
					(xy 37.77234 -94.0816) (xy 37.77234 -93.5736) (xy 38.15334 -93.5736) (xy 38.15334 -94.0816)
				)
			)
		)
		(zone
			(layer "F.Cu")
			(hatch none 0.5)
			(connect_pads
				(clearance 0)
			)
			(min_thickness 0.25)
			(keepout
				(tracks allowed)
				(vias not_allowed)
				(pads allowed)
				(copperpour not_allowed)
				(footprints allowed)
			)
			(placement
				(enabled no)
				(sheetname "")
			)
			(fill
				(thermal_gap 0.5)
				(thermal_bridge_width 0.5)
				(island_removal_mode 0)
			)
			(polygon
				(pts
					(xy 38.15334 -94.0816) (xy 38.15334 -93.5736) (xy 37.77234 -93.5736) (xy 37.77234 -94.0816)
				)
			)
		)
	)
	(footprint ""
		(layer "F.Cu")
		(at -3.405124 -16.925798)
		(property "Reference" "L1F1"
			(at 0 0 0)
			(layer "F.SilkS")
			(hide yes)
			(effects
				(font
					(size 1.27 1.27)
				)
			)
		)
		(property "Value" "*"
			(at -3.5941 0.3429 0)
			(unlocked yes)
			(layer "F.Fab")
			(hide yes)
			(effects
				(font
					(size 1.27 1.016)
					(thickness 0.1524)
				)
			)
		)
		(property "Device Type" "IND-100NH-35-GP_DISCRET-G8-INDA"
			(at -3.5941 -1.1811 0)
			(unlocked yes)
			(layer "F.Fab")
			(hide yes)
			(effects
				(font
					(size 1.27 1.016)
					(thickness 0.1524)
				)
			)
		)
		(duplicate_pad_numbers_are_jumpers no)
		(fp_line
			(start -2.2479 -2.794)
			(end 2.2479 -2.794)
			(stroke
				(width 0.1524)
				(type default)
			)
			(layer "F.SilkS")
		)
		(fp_line
			(start -2.2479 2.794)
			(end -2.2479 -2.794)
			(stroke
				(width 0.1524)
				(type default)
			)
			(layer "F.SilkS")
		)
		(fp_line
			(start 2.2479 -2.794)
			(end 2.2479 2.794)
			(stroke
				(width 0.1524)
				(type default)
			)
			(layer "F.SilkS")
		)
		(fp_line
			(start 2.2479 2.794)
			(end -2.2479 2.794)
			(stroke
				(width 0.1524)
				(type default)
			)
			(layer "F.SilkS")
		)
		(fp_rect
			(start -1.9939 1.9939)
			(end 1.9939 -1.9939)
			(stroke
				(width 0)
				(type default)
			)
			(fill no)
			(layer "F.CrtYd")
		)
		(fp_poly
			(pts
				(xy -2.5019 2.8702) (xy -2.5019 1.9939) (xy 1.9939 1.9939) (xy 1.9939 -1.9939) (xy -1.9939 -1.9939)
				(xy -1.9939 1.9812) (xy -2.5019 1.9812) (xy -2.5019 -2.8702) (xy 2.5019 -2.8702) (xy 2.5019 2.8702)
			)
			(stroke
				(width 0)
				(type default)
			)
			(fill no)
			(layer "F.CrtYd")
		)
		(fp_rect
			(start -2.5019 2.8702)
			(end 2.5019 -2.8702)
			(stroke
				(width 0)
				(type default)
			)
			(fill no)
			(layer "F.Fab")
		)
		(pad "1" smd rect
			(at 0 -1.745996)
			(size 1.5494 1.6002)
			(layers "F.Cu" "F.Mask" "F.Paste")
			(net "P12V_STBY")
		)
		(pad "2" smd rect
			(at 0 1.745996)
			(size 1.5494 1.6002)
			(layers "F.Cu" "F.Mask" "F.Paste")
			(net "VR_FET_SW_P12V_STBY_PVDDQ_GHJ")
		)
	)
	(footprint ""
		(layer "F.Cu")
		(at 436.499 -21.1455)
		(property "Reference" "R10W2"
			(at -0.8382 -0.67818 0)
			(unlocked yes)
			(layer "F.SilkS")
			(effects
				(font
					(size 0.4064 0.254)
					(thickness 0.1524)
				)
				(justify left)
			)
		)
		(property "Value" ""
			(at 0 0 0)
			(layer "F.Fab")
			(effects
				(font
					(size 1.27 1.27)
				)
			)
		)
		(duplicate_pad_numbers_are_jumpers no)
		(fp_poly
			(pts
				(xy -0.2794 -0.1016) (xy 0.2794 -0.1016) (xy 0.2794 0.9906) (xy -0.2794 0.9906)
			)
			(stroke
				(width 0)
				(type default)
			)
			(fill no)
			(layer "F.CrtYd")
		)
		(fp_line
			(start -0.2794 -0.1016)
			(end -0.2794 0.9906)
			(stroke
				(width 0.1)
				(type default)
			)
			(layer "F.Fab")
		)
		(fp_line
			(start -0.2794 0.9906)
			(end 0.2794 0.9906)
			(stroke
				(width 0.1)
				(type default)
			)
			(layer "F.Fab")
		)
		(fp_line
			(start 0.2794 -0.1016)
			(end -0.2794 -0.1016)
			(stroke
				(width 0.1)
				(type default)
			)
			(layer "F.Fab")
		)
		(fp_line
			(start 0.2794 0.9906)
			(end 0.2794 -0.1016)
			(stroke
				(width 0.1)
				(type default)
			)
			(layer "F.Fab")
		)
		(pad "1" smd rect
			(at 0 0)
			(size 0.508 0.508)
			(layers "F.Cu" "F.Mask" "F.Paste")
			(net "P3V3_STBY")
		)
		(pad "2" smd rect
			(at 0 0.889)
			(size 0.508 0.508)
			(layers "F.Cu" "F.Mask" "F.Paste")
			(net "PUMP_TACH0")
		)
		(zone
			(layer "F.Cu")
			(hatch none 0.5)
			(connect_pads
				(clearance 0)
			)
			(min_thickness 0.25)
			(keepout
				(tracks allowed)
				(vias not_allowed)
				(pads allowed)
				(copperpour not_allowed)
				(footprints allowed)
			)
			(placement
				(enabled no)
				(sheetname "")
			)
			(fill
				(thermal_gap 0.5)
				(thermal_bridge_width 0.5)
				(island_removal_mode 0)
			)
			(polygon
				(pts
					(xy 436.245 -20.8915) (xy 436.753 -20.8915) (xy 436.753 -20.5105) (xy 436.245 -20.5105)
				)
			)
		)
		(zone
			(layer "F.Cu")
			(hatch none 0.5)
			(connect_pads
				(clearance 0)
			)
			(min_thickness 0.25)
			(keepout
				(tracks not_allowed)
				(vias allowed)
				(pads allowed)
				(copperpour not_allowed)
				(footprints allowed)
			)
			(placement
				(enabled no)
				(sheetname "")
			)
			(fill
				(thermal_gap 0.5)
				(thermal_bridge_width 0.5)
				(island_removal_mode 0)
			)
			(polygon
				(pts
					(xy 436.245 -20.5105) (xy 436.753 -20.5105) (xy 436.753 -20.8915) (xy 436.245 -20.8915)
				)
			)
		)
	)
)
